#ISCELL
  mstr_misc dns *
  *
#ISCELL
  pure_quanta quanta_title_block_c *
  *
#ISCELL
  pure_quanta_power universal_gnd *
  page177_i1
#ISCELL
  standard offpage *
  page177_i10
#ISCELL
  pure_quanta_power universal_gnd *
  page177_i11
#CELL
  pure_quanta q_cap *
  page177_i12
#CELL
  pure_quanta q_res *
  page177_i13
#ISCELL
  pure_quanta_power vcc_core *
  page177_i14
#ISCELL
  pure_quanta_power universal_gnd *
  page177_i15
#CELL
  pure_quanta q_cap *
  page177_i16
#ISCELL
  pure_quanta_power universal_gnd *
  page177_i17
#CELL
  pure_quanta q_res *
  page177_i18
#ISCELL
  standard offpage *
  page177_i19
#CELL
  pure_quanta q_cap *
  page177_i2
#ISCELL
  standard offpage *
  page177_i20
#CELL
  pure_quanta isl99390frztr5935 *
  page177_i21
#ISCELL
  pure_quanta_power universal_gnd *
  page177_i22
#CELL
  pure_quanta isl99390frztr5935 *
  page177_i23
#CELL
  pure_quanta q_cap *
  page177_i24
#ISCELL
  pure_quanta_power universal_gnd *
  page177_i25
#ISCELL
  standard offpage *
  page177_i26
#ISCELL
  standard offpage *
  page177_i27
#CELL
  pure_quanta q_cap *
  page177_i28
#ISCELL
  pure_quanta_power universal_gnd *
  page177_i29
#ISCELL
  pure_quanta_power universal_gnd *
  page177_i3
#CELL
  pure_quanta q_res *
  page177_i30
#ISCELL
  pure_quanta_power universal_gnd *
  page177_i31
#CELL
  pure_quanta q_cap *
  page177_i32
#ISCELL
  pure_quanta_power vcc_core *
  page177_i33
#CELL
  pure_quanta q_cap *
  page177_i34
#ISCELL
  pure_quanta_power universal_gnd *
  page177_i35
#CELL
  pure_quanta q_res *
  page177_i36
#CELL
  pure_quanta q_res *
  page177_i37
#CELL
  pure_quanta q_cap *
  page177_i38
#ISCELL
  standard offpage *
  page177_i39
#CELL
  pure_quanta q_res *
  page177_i4
#CELL
  pure_quanta q_res *
  page177_i40
#CELL
  pure_quanta q_cap *
  page177_i41
#CELL
  pure_quanta q_inductor4p_14 *
  page177_i42
#CELL
  pure_quanta q_cap *
  page177_i43
#CELL
  pure_quanta q_cap *
  page177_i44
#ISCELL
  pure_quanta_power universal_gnd *
  page177_i45
#CELL
  pure_quanta q_res *
  page177_i46
#CELL
  pure_quanta q_cap *
  page177_i47
#ISCELL
  pure_quanta_power universal_gnd *
  page177_i48
#CELL
  pure_quanta q_cap *
  page177_i49
#ISCELL
  standard offpage *
  page177_i5
#ISCELL
  pure_quanta_power vcc_core *
  page177_i50
#CELL
  pure_quanta q_res *
  page177_i51
#ISCELL
  pure_quanta_power universal_gnd *
  page177_i52
#ISCELL
  pure_quanta_power universal_gnd *
  page177_i53
#CELL
  pure_quanta q_cap *
  page177_i54
#CELL
  pure_quanta q_cap *
  page177_i55
#ISCELL
  pure_quanta_power vcc_core *
  page177_i56
#CELL
  pure_quanta q_res *
  page177_i57
#CELL
  pure_quanta q_cap *
  page177_i58
#ISCELL
  standard offpage *
  page177_i59
#ISCELL
  pure_quanta_power universal_gnd *
  page177_i6
#CELL
  pure_quanta q_cap *
  page177_i60
#CELL
  pure_quanta q_cap *
  page177_i61
#CELL
  pure_quanta q_cap *
  page177_i62
#ISCELL
  pure_quanta_power universal_gnd *
  page177_i63
#CELL
  pure_quanta q_inductor4p_14 *
  page177_i64
#CELL
  pure_quanta q_cap *
  page177_i65
#CELL
  pure_quanta q_cap *
  page177_i66
#ISCELL
  pure_quanta_power vcc_core *
  page177_i67
#ISCELL
  standard offpage *
  page177_i68
#CELL
  pure_quanta q_cap *
  page177_i69
#CELL
  pure_quanta q_cap *
  page177_i7
#ISCELL
  pure_quanta_power universal_gnd *
  page177_i70
#CELL
  pure_quanta q_cap *
  page177_i71
#ISCELL
  pure_quanta_power vcc_core *
  page177_i72
#ISCELL
  standard offpage *
  page177_i8
#ISCELL
  standard offpage *
  page177_i9
